# BASEBOARD_FAB2 (Tioga Pass) — schematic netlist excerpt (pin names and nets, part order shuffled) for the footprints in the layout excerpt that follows; sources: Cadence DE-HDL packaged netlist, KiCad conversion of Wiwynn_Tioga_Pass_MB.brd

S9A1  SWITCH_D37771002  IC  pkg SM  page 175
  PIN1  = FM_DEBUG_RST_BTN_N
  PIN2  = FM_DEBUG_RST_BTN_N
  PIN3  = GND
  PIN4  = GND

R10W3  RES  4.75K 1% CHIP  pkg 0402  page 251 : A = P5V_STBY ; B = PUMP_PWM_OUT_R
C1E9  CAP_A  22.0UF 4V 20% X6S  pkg 0603V  page 207 : A = PVCCIN_CPU1 ; B = GND

(kicad_pcb
	(version 20260206)
	(generator "pcbnew")
	(generator_version "10.0")
	(general
		(thickness 1.6)
		(legacy_teardrops no)
	)
	(paper "A4")
	(title_block
		(title "Wiwynn_Tioga_Pass_MB.brd")
		(comment 1 "Tioga Pass / footprints 504-506 of 4770")
	)
	(layers
		(0 "F.Cu" signal "TOP")
		(4 "In1.Cu" signal "L2GND")
		(6 "In2.Cu" signal "L3")
		(8 "In3.Cu" signal "L4GND")
		(10 "In4.Cu" signal "L5")
		(12 "In5.Cu" signal "L6GND")
		(14 "In6.Cu" signal "L7VCC")
		(16 "In7.Cu" signal "L8VCC")
		(18 "In8.Cu" signal "L9GND")
		(20 "In9.Cu" signal "L10")
		(22 "In10.Cu" signal "L11GND")
		(24 "In11.Cu" signal "L12")
		(26 "In12.Cu" signal "L13GND")
		(2 "B.Cu" signal "BOTTOM")
		(9 "F.Adhes" user "F.Adhesive")
		(11 "B.Adhes" user "B.Adhesive")
		(13 "F.Paste" user "Package Geometry/Pastemask Top")
		(15 "B.Paste" user "Package Geometry/Pastemask Bottom")
		(5 "F.SilkS" user "Ref Des/Silkscreen Top")
		(7 "B.SilkS" user "Ref Des/Silkscreen Bottom")
		(1 "F.Mask" user "Board Geometry/Soldermask Top")
		(3 "B.Mask" user "Board Geometry/Soldermask Bottom")
		(17 "Dwgs.User" user "User.Drawings")
		(19 "Cmts.User" user "User.Comments")
		(21 "Eco1.User" user "User.Eco1")
		(23 "Eco2.User" user "User.Eco2")
		(25 "Edge.Cuts" user "Board Geometry/Outline")
		(27 "Margin" user)
		(31 "F.CrtYd" user "Package Geometry/Place Bound Top")
		(29 "B.CrtYd" user "Package Geometry/Place Bound Bottom")
		(35 "F.Fab" user "Ref Des/Assembly Top")
		(33 "B.Fab" user "Ref Des/Assembly Bottom")
	)
	(footprint ""
		(layer "F.Cu")
		(at 49.4284 -59.143392 180)
		(property "Reference" "C1E9"
			(at 0 0 180)
			(layer "F.SilkS")
			(hide yes)
			(effects
				(font
					(size 1.27 1.27)
				)
			)
		)
		(property "Value" ""
			(at 0 0 180)
			(layer "F.Fab")
			(effects
				(font
					(size 1.27 1.27)
				)
			)
		)
		(duplicate_pad_numbers_are_jumpers no)
		(fp_poly
			(pts
				(xy -0.4953 -0.2032) (xy 0.4953 -0.2032) (xy 0.4953 1.6002) (xy -0.4953 1.6002)
			)
			(stroke
				(width 0)
				(type default)
			)
			(fill no)
			(layer "F.CrtYd")
		)
		(fp_line
			(start 0.4953 1.6002)
			(end -0.4953 1.6002)
			(stroke
				(width 0.1)
				(type default)
			)
			(layer "F.Fab")
		)
		(fp_line
			(start 0.4953 -0.2032)
			(end 0.4953 1.6002)
			(stroke
				(width 0.1)
				(type default)
			)
			(layer "F.Fab")
		)
		(fp_line
			(start -0.4953 1.6002)
			(end -0.4953 -0.2032)
			(stroke
				(width 0.1)
				(type default)
			)
			(layer "F.Fab")
		)
		(fp_line
			(start -0.4953 -0.2032)
			(end 0.4953 -0.2032)
			(stroke
				(width 0.1)
				(type default)
			)
			(layer "F.Fab")
		)
		(pad "1" smd rect
			(at 0 0 180)
			(size 0.762 0.889)
			(layers "F.Cu" "F.Mask" "F.Paste")
			(net "PVCCIN_CPU1")
		)
		(pad "2" smd rect
			(at 0 1.397 180)
			(size 0.762 0.889)
			(layers "F.Cu" "F.Mask" "F.Paste")
			(net "GND")
		)
		(zone
			(layer "F.Cu")
			(hatch none 0.5)
			(connect_pads
				(clearance 0)
			)
			(min_thickness 0.25)
			(keepout
				(tracks not_allowed)
				(vias allowed)
				(pads allowed)
				(copperpour not_allowed)
				(footprints allowed)
			)
			(placement
				(enabled no)
				(sheetname "")
			)
			(fill
				(thermal_gap 0.5)
				(thermal_bridge_width 0.5)
				(island_removal_mode 0)
			)
			(polygon
				(pts
					(xy 49.8094 -59.587892) (xy 49.0474 -59.587892) (xy 49.0474 -60.095892) (xy 49.8094 -60.095892)
				)
			)
		)
	)
	(footprint ""
		(layer "F.Cu")
		(at 487.554016 -155.702254 -90)
		(property "Reference" "S9A1"
			(at -1.97485 3.5941 0)
			(unlocked yes)
			(layer "F.SilkS")
			(effects
				(font
					(size 0.7874 0.5842)
					(thickness 0.1524)
				)
				(justify left)
			)
		)
		(property "Value" ""
			(at 0 0 270)
			(layer "F.Fab")
			(effects
				(font
					(size 1.27 1.27)
				)
			)
		)
		(duplicate_pad_numbers_are_jumpers no)
		(fp_line
			(start 1.800098 5.3721)
			(end 3.022092 5.3721)
			(stroke
				(width 0.1524)
				(type default)
			)
			(layer "F.SilkS")
		)
		(fp_line
			(start -0.7112 0.978154)
			(end -0.7112 3.52044)
			(stroke
				(width 0.1524)
				(type default)
			)
			(layer "F.SilkS")
		)
		(fp_line
			(start 5.5372 0.973836)
			(end 5.5372 3.52044)
			(stroke
				(width 0.1524)
				(type default)
			)
			(layer "F.SilkS")
		)
		(fp_line
			(start 3.024632 -0.8763)
			(end 1.800098 -0.8763)
			(stroke
				(width 0.1524)
				(type default)
			)
			(layer "F.SilkS")
		)
		(fp_circle
			(center -1.972818 -0.651002)
			(end -1.972818 -0.778002)
			(stroke
				(width 0.254)
				(type default)
			)
			(fill no)
			(layer "F.SilkS")
		)
		(fp_rect
			(start -0.7112 5.3721)
			(end 5.5372 -0.8763)
			(stroke
				(width 0)
				(type default)
			)
			(fill no)
			(layer "F.CrtYd")
		)
		(fp_line
			(start -0.7112 5.3721)
			(end -0.7112 -0.8763)
			(stroke
				(width 0.1)
				(type default)
			)
			(layer "F.Fab")
		)
		(fp_line
			(start 5.5372 5.3721)
			(end -0.7112 5.3721)
			(stroke
				(width 0.1)
				(type default)
			)
			(layer "F.Fab")
		)
		(fp_line
			(start -0.7112 -0.8763)
			(end 5.5372 -0.8763)
			(stroke
				(width 0.1)
				(type default)
			)
			(layer "F.Fab")
		)
		(fp_line
			(start 5.5372 -0.8763)
			(end 5.5372 5.3721)
			(stroke
				(width 0.1)
				(type default)
			)
			(layer "F.Fab")
		)
		(fp_circle
			(center -1.972818 -0.651002)
			(end -1.972818 -0.778002)
			(stroke
				(width 0.254)
				(type default)
			)
			(fill no)
			(layer "F.Fab")
		)
		(fp_text user "4"
			(at 5.881624 5.809996 0)
			(unlocked yes)
			(layer "F.SilkS")
			(effects
				(font
					(size 0.7874 0.5842)
					(thickness 0.1524)
				)
				(justify left)
			)
		)
		(fp_text user "2"
			(at 5.373624 -0.735584 0)
			(unlocked yes)
			(layer "F.SilkS")
			(effects
				(font
					(size 0.7874 0.5842)
					(thickness 0.1524)
				)
				(justify left)
			)
		)
		(fp_text user "4"
			(at 6.354064 3.663696 0)
			(unlocked yes)
			(layer "F.Fab")
			(effects
				(font
					(size 0.635 0.635)
					(thickness 0.1524)
				)
				(justify left)
			)
		)
		(fp_text user "2"
			(at 6.338316 1.57861 0)
			(unlocked yes)
			(layer "F.Fab")
			(effects
				(font
					(size 0.635 0.635)
					(thickness 0.1524)
				)
				(justify left)
			)
		)
		(pad "1" smd rect
			(at 0 0 270)
			(size 2.921 1.27)
			(layers "F.Cu" "F.Mask" "F.Paste")
			(net "FM_DEBUG_RST_BTN_N")
		)
		(pad "2" smd rect
			(at 4.826 0 270)
			(size 2.921 1.27)
			(layers "F.Cu" "F.Mask" "F.Paste")
			(net "FM_DEBUG_RST_BTN_N")
		)
		(pad "3" smd rect
			(at 0 4.4958 270)
			(size 2.921 1.27)
			(layers "F.Cu" "F.Mask" "F.Paste")
			(net "GND")
		)
		(pad "4" smd rect
			(at 4.826 4.4958 270)
			(size 2.921 1.27)
			(layers "F.Cu" "F.Mask" "F.Paste")
			(net "GND")
		)
	)
	(footprint ""
		(layer "F.Cu")
		(at 427.355 -22.86 90)
		(property "Reference" "R10W3"
			(at -0.8382 -0.67818 90)
			(unlocked yes)
			(layer "F.SilkS")
			(effects
				(font
					(size 0.4064 0.254)
					(thickness 0.1524)
				)
				(justify left)
			)
		)
		(property "Value" ""
			(at 0 0 90)
			(layer "F.Fab")
			(effects
				(font
					(size 1.27 1.27)
				)
			)
		)
		(duplicate_pad_numbers_are_jumpers no)
		(fp_poly
			(pts
				(xy -0.2794 -0.1016) (xy 0.2794 -0.1016) (xy 0.2794 0.9906) (xy -0.2794 0.9906)
			)
			(stroke
				(width 0)
				(type default)
			)
			(fill no)
			(layer "F.CrtYd")
		)
		(fp_line
			(start 0.2794 -0.1016)
			(end -0.2794 -0.1016)
			(stroke
				(width 0.1)
				(type default)
			)
			(layer "F.Fab")
		)
		(fp_line
			(start -0.2794 -0.1016)
			(end -0.2794 0.9906)
			(stroke
				(width 0.1)
				(type default)
			)
			(layer "F.Fab")
		)
		(fp_line
			(start 0.2794 0.9906)
			(end 0.2794 -0.1016)
			(stroke
				(width 0.1)
				(type default)
			)
			(layer "F.Fab")
		)
		(fp_line
			(start -0.2794 0.9906)
			(end 0.2794 0.9906)
			(stroke
				(width 0.1)
				(type default)
			)
			(layer "F.Fab")
		)
		(pad "1" smd rect
			(at 0 0 90)
			(size 0.508 0.508)
			(layers "F.Cu" "F.Mask" "F.Paste")
			(net "P5V_STBY")
		)
		(pad "2" smd rect
			(at 0 0.889 90)
			(size 0.508 0.508)
			(layers "F.Cu" "F.Mask" "F.Paste")
			(net "PUMP_PWM_OUT_R")
		)
		(zone
			(layer "F.Cu")
			(hatch none 0.5)
			(connect_pads
				(clearance 0)
			)
			(min_thickness 0.25)
			(keepout
				(tracks allowed)
				(vias not_allowed)
				(pads allowed)
				(copperpour not_allowed)
				(footprints allowed)
			)
			(placement
				(enabled no)
				(sheetname "")
			)
			(fill
				(thermal_gap 0.5)
				(thermal_bridge_width 0.5)
				(island_removal_mode 0)
			)
			(polygon
				(pts
					(xy 427.609 -22.606) (xy 427.609 -23.114) (xy 427.99 -23.114) (xy 427.99 -22.606)
				)
			)
		)
		(zone
			(layer "F.Cu")
			(hatch none 0.5)
			(connect_pads
				(clearance 0)
			)
			(min_thickness 0.25)
			(keepout
				(tracks not_allowed)
				(vias allowed)
				(pads allowed)
				(copperpour not_allowed)
				(footprints allowed)
			)
			(placement
				(enabled no)
				(sheetname "")
			)
			(fill
				(thermal_gap 0.5)
				(thermal_bridge_width 0.5)
				(island_removal_mode 0)
			)
			(polygon
				(pts
					(xy 427.99 -22.606) (xy 427.99 -23.114) (xy 427.609 -23.114) (xy 427.609 -22.606)
				)
			)
		)
	)
)
